# T6G (Grand Teton) — schematic netlist excerpt (pin names and nets, part order shuffled) for the footprints in the layout excerpt that follows; sources: Cadence DE-HDL packaged netlist, KiCad conversion of 04192023_DAF0TMB3IC0_F0TG_MB_C_brd_V02_OCP.brd

C2573  Q_CAP  22UF 4V 20% X6S  pkg C0402  page 70 : A = PVDDCR_SOC_P0 ; B = GND
R1143  Q_RES  0 5% CHIP  pkg 0402LF  page 136 : A = OCP_V3_1_P3V3_PLD_PWRGD ; B = OCP_V3_1_P3V3_PLD_R_PWRGD

(kicad_pcb
	(version 20260206)
	(generator "pcbnew")
	(generator_version "10.0")
	(general
		(thickness 1.6)
		(legacy_teardrops no)
	)
	(paper "A4")
	(title_block
		(title "04192023_DAF0TMB3IC0_F0TG_MB_C_brd_V02_OCP.brd")
		(comment 1 "Grand Teton / footprints 1732-1733 of 8354")
	)
	(layers
		(0 "F.Cu" signal "TOP")
		(4 "In1.Cu" signal "GND")
		(6 "In2.Cu" signal "IN1")
		(8 "In3.Cu" signal "GND1")
		(10 "In4.Cu" signal "IN2")
		(12 "In5.Cu" signal "GND2")
		(14 "In6.Cu" signal "IN3")
		(16 "In7.Cu" signal "GND3")
		(18 "In8.Cu" signal "VCC")
		(20 "In9.Cu" signal "VCC1")
		(22 "In10.Cu" signal "GND4")
		(24 "In11.Cu" signal "IN4")
		(26 "In12.Cu" signal "GND5")
		(28 "In13.Cu" signal "IN5")
		(30 "In14.Cu" signal "GND6")
		(32 "In15.Cu" signal "IN6")
		(34 "In16.Cu" signal "GND7")
		(2 "B.Cu" signal "BOTTOM")
		(9 "F.Adhes" user "F.Adhesive")
		(11 "B.Adhes" user "B.Adhesive")
		(13 "F.Paste" user "Package Geometry/Pastemask Top")
		(15 "B.Paste" user "Package Geometry/Pastemask Bottom")
		(5 "F.SilkS" user "Ref Des/Silkscreen Top")
		(7 "B.SilkS" user "Ref Des/Silkscreen Bottom")
		(1 "F.Mask" user "Board Geometry/Soldermask Top")
		(3 "B.Mask" user "Board Geometry/Soldermask Bottom")
		(17 "Dwgs.User" user "User.Drawings")
		(19 "Cmts.User" user "User.Comments")
		(21 "Eco1.User" user "User.Eco1")
		(23 "Eco2.User" user "User.Eco2")
		(25 "Edge.Cuts" user "Board Geometry/Outline")
		(27 "Margin" user)
		(31 "F.CrtYd" user "Package Geometry/Place Bound Top")
		(29 "B.CrtYd" user "Package Geometry/Place Bound Bottom")
		(35 "F.Fab" user "Ref Des/Assembly Top")
		(33 "B.Fab" user "Ref Des/Assembly Bottom")
	)
	(footprint ""
		(layer "F.Cu")
		(at 167.894 -99.06 180)
		(property "Reference" "R1143"
			(at 0 0 180)
			(layer "F.SilkS")
			(hide yes)
			(effects
				(font
					(size 1.27 1.27)
				)
			)
		)
		(property "Value" ""
			(at 0 0 180)
			(layer "F.Fab")
			(effects
				(font
					(size 1.27 1.27)
				)
			)
		)
		(duplicate_pad_numbers_are_jumpers no)
		(fp_line
			(start 0.7874 0.4064)
			(end -0.7874 0.4064)
			(stroke
				(width 0.1524)
				(type default)
			)
			(layer "F.SilkS")
		)
		(fp_line
			(start 0.7874 -0.4064)
			(end 0.7874 0.4064)
			(stroke
				(width 0.1524)
				(type default)
			)
			(layer "F.SilkS")
		)
		(fp_line
			(start -0.7874 0.4064)
			(end -0.7874 -0.4064)
			(stroke
				(width 0.1524)
				(type default)
			)
			(layer "F.SilkS")
		)
		(fp_line
			(start -0.7874 -0.4064)
			(end 0.7874 -0.4064)
			(stroke
				(width 0.1524)
				(type default)
			)
			(layer "F.SilkS")
		)
		(fp_line
			(start 0.67945 0.3048)
			(end 0.120396 0.3048)
			(stroke
				(width 0.1)
				(type default)
			)
			(layer "F.Fab")
		)
		(fp_line
			(start 0.67945 -0.3048)
			(end 0.67945 0.3048)
			(stroke
				(width 0.1)
				(type default)
			)
			(layer "F.Fab")
		)
		(fp_line
			(start 0.12065 -0.2794)
			(end 0.12065 -0.3048)
			(stroke
				(width 0.1)
				(type default)
			)
			(layer "F.Fab")
		)
		(fp_line
			(start 0.12065 -0.3048)
			(end 0.67945 -0.3048)
			(stroke
				(width 0.1)
				(type default)
			)
			(layer "F.Fab")
		)
		(fp_line
			(start 0.120396 0.3048)
			(end 0.120396 0.2794)
			(stroke
				(width 0.1)
				(type default)
			)
			(layer "F.Fab")
		)
		(fp_line
			(start 0.120396 0.2794)
			(end -0.12065 0.2794)
			(stroke
				(width 0.1)
				(type default)
			)
			(layer "F.Fab")
		)
		(fp_line
			(start -0.12065 0.3048)
			(end -0.67945 0.3048)
			(stroke
				(width 0.1)
				(type default)
			)
			(layer "F.Fab")
		)
		(fp_line
			(start -0.12065 0.2794)
			(end -0.12065 0.3048)
			(stroke
				(width 0.1)
				(type default)
			)
			(layer "F.Fab")
		)
		(fp_line
			(start -0.12065 -0.2794)
			(end 0.12065 -0.2794)
			(stroke
				(width 0.1)
				(type default)
			)
			(layer "F.Fab")
		)
		(fp_line
			(start -0.12065 -0.305054)
			(end -0.12065 -0.2794)
			(stroke
				(width 0.1)
				(type default)
			)
			(layer "F.Fab")
		)
		(fp_line
			(start -0.67945 0.3048)
			(end -0.67945 -0.305054)
			(stroke
				(width 0.1)
				(type default)
			)
			(layer "F.Fab")
		)
		(fp_line
			(start -0.67945 -0.305054)
			(end -0.12065 -0.305054)
			(stroke
				(width 0.1)
				(type default)
			)
			(layer "F.Fab")
		)
		(pad "1" smd circle
			(at -0.40005 0 180)
			(size 0 0)
			(layers "F.Cu" "F.Mask" "F.Paste")
			(net "OCP_V3_1_P3V3_PLD_PWRGD")
		)
		(pad "2" smd circle
			(at 0.40005 0 180)
			(size 0 0)
			(layers "F.Cu" "F.Mask" "F.Paste")
			(net "OCP_V3_1_P3V3_PLD_R_PWRGD")
		)
	)
	(footprint ""
		(layer "F.Cu")
		(at 361.046014 -257.744976)
		(property "Reference" "C2573"
			(at 0 0 0)
			(layer "F.SilkS")
			(hide yes)
			(effects
				(font
					(size 1.27 1.27)
				)
			)
		)
		(property "Value" ""
			(at 0 0 0)
			(layer "F.Fab")
			(effects
				(font
					(size 1.27 1.27)
				)
			)
		)
		(duplicate_pad_numbers_are_jumpers no)
		(fp_line
			(start -0.7874 -0.4064)
			(end 0.7874 -0.4064)
			(stroke
				(width 0.1524)
				(type default)
			)
			(layer "F.SilkS")
		)
		(fp_line
			(start -0.7874 0.4064)
			(end -0.7874 -0.4064)
			(stroke
				(width 0.1524)
				(type default)
			)
			(layer "F.SilkS")
		)
		(fp_line
			(start 0.7874 -0.4064)
			(end 0.7874 0.4064)
			(stroke
				(width 0.1524)
				(type default)
			)
			(layer "F.SilkS")
		)
		(fp_line
			(start 0.7874 0.4064)
			(end -0.7874 0.4064)
			(stroke
				(width 0.1524)
				(type default)
			)
			(layer "F.SilkS")
		)
		(fp_line
			(start -0.67945 -0.305054)
			(end -0.12065 -0.305054)
			(stroke
				(width 0.1)
				(type default)
			)
			(layer "F.Fab")
		)
		(fp_line
			(start -0.67945 0.3048)
			(end -0.67945 -0.305054)
			(stroke
				(width 0.1)
				(type default)
			)
			(layer "F.Fab")
		)
		(fp_line
			(start -0.12065 -0.305054)
			(end -0.12065 -0.2794)
			(stroke
				(width 0.1)
				(type default)
			)
			(layer "F.Fab")
		)
		(fp_line
			(start -0.12065 -0.2794)
			(end 0.12065 -0.2794)
			(stroke
				(width 0.1)
				(type default)
			)
			(layer "F.Fab")
		)
		(fp_line
			(start -0.12065 0.2794)
			(end -0.12065 0.3048)
			(stroke
				(width 0.1)
				(type default)
			)
			(layer "F.Fab")
		)
		(fp_line
			(start -0.12065 0.3048)
			(end -0.67945 0.3048)
			(stroke
				(width 0.1)
				(type default)
			)
			(layer "F.Fab")
		)
		(fp_line
			(start 0.120396 0.2794)
			(end -0.12065 0.2794)
			(stroke
				(width 0.1)
				(type default)
			)
			(layer "F.Fab")
		)
		(fp_line
			(start 0.120396 0.3048)
			(end 0.120396 0.2794)
			(stroke
				(width 0.1)
				(type default)
			)
			(layer "F.Fab")
		)
		(fp_line
			(start 0.12065 -0.3048)
			(end 0.67945 -0.3048)
			(stroke
				(width 0.1)
				(type default)
			)
			(layer "F.Fab")
		)
		(fp_line
			(start 0.12065 -0.2794)
			(end 0.12065 -0.3048)
			(stroke
				(width 0.1)
				(type default)
			)
			(layer "F.Fab")
		)
		(fp_line
			(start 0.67945 -0.3048)
			(end 0.67945 0.3048)
			(stroke
				(width 0.1)
				(type default)
			)
			(layer "F.Fab")
		)
		(fp_line
			(start 0.67945 0.3048)
			(end 0.120396 0.3048)
			(stroke
				(width 0.1)
				(type default)
			)
			(layer "F.Fab")
		)
		(pad "1" smd circle
			(at -0.40005 0)
			(size 0 0)
			(layers "F.Cu" "F.Mask" "F.Paste")
			(net "PVDDCR_SOC_P0")
		)
		(pad "2" smd circle
			(at 0.40005 0)
			(size 0 0)
			(layers "F.Cu" "F.Mask" "F.Paste")
			(net "GND")
		)
	)
)
